(kicad_pcb
	(version 20260206)
	(generator "pcbnew")
	(generator_version "10.0")
	(general
		(thickness 1.6)
		(legacy_teardrops no)
	)
	(paper "A4")
	(title_block
		(title "01162023_DA0F0TEBIF0_F0T_Expander_BD_F_brd_V02_OCP.brd")
		(comment 1 "Grand Teton / footprints 5070-5076 of 9728")
	)
	(layers
		(0 "F.Cu" signal "TOP")
		(4 "In1.Cu" signal "GND")
		(6 "In2.Cu" signal "VCC")
		(8 "In3.Cu" signal "VCC1")
		(10 "In4.Cu" signal "GND1")
		(12 "In5.Cu" signal "IN1")
		(14 "In6.Cu" signal "GND2")
		(16 "In7.Cu" signal "IN2")
		(18 "In8.Cu" signal "GND3")
		(20 "In9.Cu" signal "IN3")
		(22 "In10.Cu" signal "GND4")
		(24 "In11.Cu" signal "IN4")
		(26 "In12.Cu" signal "GND5")
		(28 "In13.Cu" signal "IN5")
		(30 "In14.Cu" signal "GND6")
		(32 "In15.Cu" signal "IN6")
		(34 "In16.Cu" signal "GND7")
		(2 "B.Cu" signal "BOTTOM")
		(9 "F.Adhes" user "F.Adhesive")
		(11 "B.Adhes" user "B.Adhesive")
		(13 "F.Paste" user "Package Geometry/Pastemask Top")
		(15 "B.Paste" user "Package Geometry/Pastemask Bottom")
		(5 "F.SilkS" user "Ref Des/Silkscreen Top")
		(7 "B.SilkS" user "Ref Des/Silkscreen Bottom")
		(1 "F.Mask" user "Board Geometry/Soldermask Top")
		(3 "B.Mask" user "Board Geometry/Soldermask Bottom")
		(17 "Dwgs.User" user "User.Drawings")
		(19 "Cmts.User" user "User.Comments")
		(21 "Eco1.User" user "User.Eco1")
		(23 "Eco2.User" user "User.Eco2")
		(25 "Edge.Cuts" user "Board Geometry/Outline")
		(27 "Margin" user)
		(31 "F.CrtYd" user "Package Geometry/Place Bound Top")
		(29 "B.CrtYd" user "Package Geometry/Place Bound Bottom")
		(35 "F.Fab" user "Ref Des/Assembly Top")
		(33 "B.Fab" user "Ref Des/Assembly Bottom")
	)
	(footprint ""
		(layer "F.Cu")
		(at 359.156 -179.07 180)
		(property "Reference" "R4676"
			(at 0 0 180)
			(layer "F.SilkS")
			(hide yes)
			(effects
				(font
					(size 1.27 1.27)
				)
			)
		)
		(property "Value" ""
			(at 0 0 180)
			(layer "F.Fab")
			(effects
				(font
					(size 1.27 1.27)
				)
			)
		)
		(duplicate_pad_numbers_are_jumpers no)
		(fp_line
			(start 0.7874 0.4064)
			(end -0.7874 0.4064)
			(stroke
				(width 0.1524)
				(type default)
			)
			(layer "F.SilkS")
		)
		(fp_line
			(start 0.7874 -0.4064)
			(end 0.7874 0.4064)
			(stroke
				(width 0.1524)
				(type default)
			)
			(layer "F.SilkS")
		)
		(fp_line
			(start -0.7874 0.4064)
			(end -0.7874 -0.4064)
			(stroke
				(width 0.1524)
				(type default)
			)
			(layer "F.SilkS")
		)
		(fp_line
			(start -0.7874 -0.4064)
			(end 0.7874 -0.4064)
			(stroke
				(width 0.1524)
				(type default)
			)
			(layer "F.SilkS")
		)
		(fp_line
			(start 0.67945 0.3048)
			(end 0.120396 0.3048)
			(stroke
				(width 0.1)
				(type default)
			)
			(layer "F.Fab")
		)
		(fp_line
			(start 0.67945 -0.3048)
			(end 0.67945 0.3048)
			(stroke
				(width 0.1)
				(type default)
			)
			(layer "F.Fab")
		)
		(fp_line
			(start 0.12065 -0.2794)
			(end 0.12065 -0.3048)
			(stroke
				(width 0.1)
				(type default)
			)
			(layer "F.Fab")
		)
		(fp_line
			(start 0.12065 -0.3048)
			(end 0.67945 -0.3048)
			(stroke
				(width 0.1)
				(type default)
			)
			(layer "F.Fab")
		)
		(fp_line
			(start 0.120396 0.3048)
			(end 0.120396 0.2794)
			(stroke
				(width 0.1)
				(type default)
			)
			(layer "F.Fab")
		)
		(fp_line
			(start 0.120396 0.2794)
			(end -0.12065 0.2794)
			(stroke
				(width 0.1)
				(type default)
			)
			(layer "F.Fab")
		)
		(fp_line
			(start -0.12065 0.3048)
			(end -0.67945 0.3048)
			(stroke
				(width 0.1)
				(type default)
			)
			(layer "F.Fab")
		)
		(fp_line
			(start -0.12065 0.2794)
			(end -0.12065 0.3048)
			(stroke
				(width 0.1)
				(type default)
			)
			(layer "F.Fab")
		)
		(fp_line
			(start -0.12065 -0.2794)
			(end 0.12065 -0.2794)
			(stroke
				(width 0.1)
				(type default)
			)
			(layer "F.Fab")
		)
		(fp_line
			(start -0.12065 -0.305054)
			(end -0.12065 -0.2794)
			(stroke
				(width 0.1)
				(type default)
			)
			(layer "F.Fab")
		)
		(fp_line
			(start -0.67945 0.3048)
			(end -0.67945 -0.305054)
			(stroke
				(width 0.1)
				(type default)
			)
			(layer "F.Fab")
		)
		(fp_line
			(start -0.67945 -0.305054)
			(end -0.12065 -0.305054)
			(stroke
				(width 0.1)
				(type default)
			)
			(layer "F.Fab")
		)
		(pad "1" smd circle
			(at -0.40005 0 180)
			(size 0 0)
			(layers "F.Cu" "F.Mask" "F.Paste")
			(net "SSD6_PEX_PWR_EN_R")
		)
		(pad "2" smd circle
			(at 0.40005 0 180)
			(size 0 0)
			(layers "F.Cu" "F.Mask" "F.Paste")
			(net "GND")
		)
	)
	(footprint ""
		(layer "F.Cu")
		(at 379.950218 -50.96383 180)
		(property "Reference" "PC563"
			(at 0 0 180)
			(layer "F.SilkS")
			(hide yes)
			(effects
				(font
					(size 1.27 1.27)
				)
			)
		)
		(property "Value" ""
			(at 0 0 180)
			(layer "F.Fab")
			(effects
				(font
					(size 1.27 1.27)
				)
			)
		)
		(duplicate_pad_numbers_are_jumpers no)
		(fp_line
			(start 1.524 0.762)
			(end -1.524 0.762)
			(stroke
				(width 0.1524)
				(type default)
			)
			(layer "F.SilkS")
		)
		(fp_line
			(start 1.524 -0.762)
			(end 1.524 0.762)
			(stroke
				(width 0.1524)
				(type default)
			)
			(layer "F.SilkS")
		)
		(fp_line
			(start -1.524 0.762)
			(end -1.524 -0.762)
			(stroke
				(width 0.1524)
				(type default)
			)
			(layer "F.SilkS")
		)
		(fp_line
			(start -1.524 -0.762)
			(end 1.524 -0.762)
			(stroke
				(width 0.1524)
				(type default)
			)
			(layer "F.SilkS")
		)
		(fp_line
			(start 1.1049 0.724916)
			(end 1.1049 -0.724916)
			(stroke
				(width 0.1)
				(type default)
			)
			(layer "F.Fab")
		)
		(fp_line
			(start 1.1049 -0.724916)
			(end -1.1049 -0.724916)
			(stroke
				(width 0.1)
				(type default)
			)
			(layer "F.Fab")
		)
		(fp_line
			(start -1.1049 0.724916)
			(end 1.1049 0.724916)
			(stroke
				(width 0.1)
				(type default)
			)
			(layer "F.Fab")
		)
		(fp_line
			(start -1.1049 -0.724916)
			(end -1.1049 0.724916)
			(stroke
				(width 0.1)
				(type default)
			)
			(layer "F.Fab")
		)
		(pad "1" smd rect
			(at -0.889 0)
			(size 1.016 1.27)
			(layers "F.Cu" "F.Mask" "F.Paste")
			(net "P3V3_SSD13")
		)
		(pad "2" smd rect
			(at 0.889 0)
			(size 1.016 1.27)
			(layers "F.Cu" "F.Mask" "F.Paste")
			(net "GND")
		)
	)
	(footprint ""
		(layer "F.Cu")
		(at 312.21934 -142.590266 180)
		(property "Reference" "C438"
			(at 0 0 180)
			(layer "F.SilkS")
			(hide yes)
			(effects
				(font
					(size 1.27 1.27)
				)
			)
		)
		(property "Value" ""
			(at 0 0 180)
			(layer "F.Fab")
			(effects
				(font
					(size 1.27 1.27)
				)
			)
		)
		(duplicate_pad_numbers_are_jumpers no)
		(fp_line
			(start 0.299974 0.150114)
			(end -0.299974 0.150114)
			(stroke
				(width 0.1)
				(type default)
			)
			(layer "F.Fab")
		)
		(fp_line
			(start 0.299974 -0.150114)
			(end 0.299974 0.150114)
			(stroke
				(width 0.1)
				(type default)
			)
			(layer "F.Fab")
		)
		(fp_line
			(start -0.299974 0.150114)
			(end -0.299974 -0.150114)
			(stroke
				(width 0.1)
				(type default)
			)
			(layer "F.Fab")
		)
		(fp_line
			(start -0.299974 -0.150114)
			(end 0.299974 -0.150114)
			(stroke
				(width 0.1)
				(type default)
			)
			(layer "F.Fab")
		)
		(pad "1" smd rect
			(at -0.2667 0 180)
			(size 0.3048 0.381)
			(layers "F.Cu" "F.Mask" "F.Paste")
			(net "P5E_PEX2_STN0_TX_DN<8>")
		)
		(pad "2" smd rect
			(at 0.2667 0 180)
			(size 0.3048 0.381)
			(layers "F.Cu" "F.Mask" "F.Paste")
			(net "P5E_PEX2_STN0_TX_C_DN<8>")
		)
	)
	(footprint ""
		(layer "F.Cu")
		(at 147.554442 -252.356874 -90)
		(property "Reference" "R1293"
			(at 0 0 270)
			(layer "F.SilkS")
			(hide yes)
			(effects
				(font
					(size 1.27 1.27)
				)
			)
		)
		(property "Value" ""
			(at 0 0 270)
			(layer "F.Fab")
			(effects
				(font
					(size 1.27 1.27)
				)
			)
		)
		(duplicate_pad_numbers_are_jumpers no)
		(fp_line
			(start -0.7874 0.4064)
			(end -0.7874 -0.4064)
			(stroke
				(width 0.1524)
				(type default)
			)
			(layer "F.SilkS")
		)
		(fp_line
			(start 0.7874 0.4064)
			(end -0.7874 0.4064)
			(stroke
				(width 0.1524)
				(type default)
			)
			(layer "F.SilkS")
		)
		(fp_line
			(start -0.7874 -0.4064)
			(end 0.7874 -0.4064)
			(stroke
				(width 0.1524)
				(type default)
			)
			(layer "F.SilkS")
		)
		(fp_line
			(start 0.7874 -0.4064)
			(end 0.7874 0.4064)
			(stroke
				(width 0.1524)
				(type default)
			)
			(layer "F.SilkS")
		)
		(fp_line
			(start -0.67945 0.3048)
			(end -0.67945 -0.305054)
			(stroke
				(width 0.1)
				(type default)
			)
			(layer "F.Fab")
		)
		(fp_line
			(start -0.12065 0.3048)
			(end -0.67945 0.3048)
			(stroke
				(width 0.1)
				(type default)
			)
			(layer "F.Fab")
		)
		(fp_line
			(start 0.120396 0.3048)
			(end 0.120396 0.2794)
			(stroke
				(width 0.1)
				(type default)
			)
			(layer "F.Fab")
		)
		(fp_line
			(start 0.67945 0.3048)
			(end 0.120396 0.3048)
			(stroke
				(width 0.1)
				(type default)
			)
			(layer "F.Fab")
		)
		(fp_line
			(start -0.12065 0.2794)
			(end -0.12065 0.3048)
			(stroke
				(width 0.1)
				(type default)
			)
			(layer "F.Fab")
		)
		(fp_line
			(start 0.120396 0.2794)
			(end -0.12065 0.2794)
			(stroke
				(width 0.1)
				(type default)
			)
			(layer "F.Fab")
		)
		(fp_line
			(start -0.12065 -0.2794)
			(end 0.12065 -0.2794)
			(stroke
				(width 0.1)
				(type default)
			)
			(layer "F.Fab")
		)
		(fp_line
			(start 0.12065 -0.2794)
			(end 0.12065 -0.3048)
			(stroke
				(width 0.1)
				(type default)
			)
			(layer "F.Fab")
		)
		(fp_line
			(start 0.12065 -0.3048)
			(end 0.67945 -0.3048)
			(stroke
				(width 0.1)
				(type default)
			)
			(layer "F.Fab")
		)
		(fp_line
			(start 0.67945 -0.3048)
			(end 0.67945 0.3048)
			(stroke
				(width 0.1)
				(type default)
			)
			(layer "F.Fab")
		)
		(fp_line
			(start -0.67945 -0.305054)
			(end -0.12065 -0.305054)
			(stroke
				(width 0.1)
				(type default)
			)
			(layer "F.Fab")
		)
		(fp_line
			(start -0.12065 -0.305054)
			(end -0.12065 -0.2794)
			(stroke
				(width 0.1)
				(type default)
			)
			(layer "F.Fab")
		)
		(pad "1" smd circle
			(at -0.40005 0 270)
			(size 0 0)
			(layers "F.Cu" "F.Mask" "F.Paste")
			(net "GND")
		)
		(pad "2" smd circle
			(at 0.40005 0 270)
			(size 0 0)
			(layers "F.Cu" "F.Mask" "F.Paste")
			(net "PEX1_MODE_SEL4")
		)
	)
	(footprint ""
		(layer "F.Cu")
		(at 138.985244 -95.814642 180)
		(property "Reference" "R1572"
			(at 0 0 180)
			(layer "F.SilkS")
			(hide yes)
			(effects
				(font
					(size 1.27 1.27)
				)
			)
		)
		(property "Value" ""
			(at 0 0 180)
			(layer "F.Fab")
			(effects
				(font
					(size 1.27 1.27)
				)
			)
		)
		(duplicate_pad_numbers_are_jumpers no)
		(fp_line
			(start 0.7874 0.4064)
			(end -0.7874 0.4064)
			(stroke
				(width 0.1524)
				(type default)
			)
			(layer "F.SilkS")
		)
		(fp_line
			(start 0.7874 -0.4064)
			(end 0.7874 0.4064)
			(stroke
				(width 0.1524)
				(type default)
			)
			(layer "F.SilkS")
		)
		(fp_line
			(start -0.7874 0.4064)
			(end -0.7874 -0.4064)
			(stroke
				(width 0.1524)
				(type default)
			)
			(layer "F.SilkS")
		)
		(fp_line
			(start -0.7874 -0.4064)
			(end 0.7874 -0.4064)
			(stroke
				(width 0.1524)
				(type default)
			)
			(layer "F.SilkS")
		)
		(fp_line
			(start 0.67945 0.3048)
			(end 0.120396 0.3048)
			(stroke
				(width 0.1)
				(type default)
			)
			(layer "F.Fab")
		)
		(fp_line
			(start 0.67945 -0.3048)
			(end 0.67945 0.3048)
			(stroke
				(width 0.1)
				(type default)
			)
			(layer "F.Fab")
		)
		(fp_line
			(start 0.12065 -0.2794)
			(end 0.12065 -0.3048)
			(stroke
				(width 0.1)
				(type default)
			)
			(layer "F.Fab")
		)
		(fp_line
			(start 0.12065 -0.3048)
			(end 0.67945 -0.3048)
			(stroke
				(width 0.1)
				(type default)
			)
			(layer "F.Fab")
		)
		(fp_line
			(start 0.120396 0.3048)
			(end 0.120396 0.2794)
			(stroke
				(width 0.1)
				(type default)
			)
			(layer "F.Fab")
		)
		(fp_line
			(start 0.120396 0.2794)
			(end -0.12065 0.2794)
			(stroke
				(width 0.1)
				(type default)
			)
			(layer "F.Fab")
		)
		(fp_line
			(start -0.12065 0.3048)
			(end -0.67945 0.3048)
			(stroke
				(width 0.1)
				(type default)
			)
			(layer "F.Fab")
		)
		(fp_line
			(start -0.12065 0.2794)
			(end -0.12065 0.3048)
			(stroke
				(width 0.1)
				(type default)
			)
			(layer "F.Fab")
		)
		(fp_line
			(start -0.12065 -0.2794)
			(end 0.12065 -0.2794)
			(stroke
				(width 0.1)
				(type default)
			)
			(layer "F.Fab")
		)
		(fp_line
			(start -0.12065 -0.305054)
			(end -0.12065 -0.2794)
			(stroke
				(width 0.1)
				(type default)
			)
			(layer "F.Fab")
		)
		(fp_line
			(start -0.67945 0.3048)
			(end -0.67945 -0.305054)
			(stroke
				(width 0.1)
				(type default)
			)
			(layer "F.Fab")
		)
		(fp_line
			(start -0.67945 -0.305054)
			(end -0.12065 -0.305054)
			(stroke
				(width 0.1)
				(type default)
			)
			(layer "F.Fab")
		)
		(pad "1" smd circle
			(at -0.40005 0 180)
			(size 0 0)
			(layers "F.Cu" "F.Mask" "F.Paste")
			(net "P3V3_AUX")
		)
		(pad "2" smd circle
			(at 0.40005 0 180)
			(size 0 0)
			(layers "F.Cu" "F.Mask" "F.Paste")
			(net "SMB_BIC_I2C9_MUX0_SSD7_R_SCL")
		)
	)
	(footprint ""
		(layer "F.Cu")
		(at 184.491884 -193.074798)
		(property "Reference" "R472"
			(at 0 0 0)
			(layer "F.SilkS")
			(hide yes)
			(effects
				(font
					(size 1.27 1.27)
				)
			)
		)
		(property "Value" ""
			(at 0 0 0)
			(layer "F.Fab")
			(effects
				(font
					(size 1.27 1.27)
				)
			)
		)
		(duplicate_pad_numbers_are_jumpers no)
		(fp_line
			(start -0.7874 -0.4064)
			(end 0.7874 -0.4064)
			(stroke
				(width 0.1524)
				(type default)
			)
			(layer "F.SilkS")
		)
		(fp_line
			(start -0.7874 0.4064)
			(end -0.7874 -0.4064)
			(stroke
				(width 0.1524)
				(type default)
			)
			(layer "F.SilkS")
		)
		(fp_line
			(start 0.7874 -0.4064)
			(end 0.7874 0.4064)
			(stroke
				(width 0.1524)
				(type default)
			)
			(layer "F.SilkS")
		)
		(fp_line
			(start 0.7874 0.4064)
			(end -0.7874 0.4064)
			(stroke
				(width 0.1524)
				(type default)
			)
			(layer "F.SilkS")
		)
		(fp_line
			(start -0.67945 -0.305054)
			(end -0.12065 -0.305054)
			(stroke
				(width 0.1)
				(type default)
			)
			(layer "F.Fab")
		)
		(fp_line
			(start -0.67945 0.3048)
			(end -0.67945 -0.305054)
			(stroke
				(width 0.1)
				(type default)
			)
			(layer "F.Fab")
		)
		(fp_line
			(start -0.12065 -0.305054)
			(end -0.12065 -0.2794)
			(stroke
				(width 0.1)
				(type default)
			)
			(layer "F.Fab")
		)
		(fp_line
			(start -0.12065 -0.2794)
			(end 0.12065 -0.2794)
			(stroke
				(width 0.1)
				(type default)
			)
			(layer "F.Fab")
		)
		(fp_line
			(start -0.12065 0.2794)
			(end -0.12065 0.3048)
			(stroke
				(width 0.1)
				(type default)
			)
			(layer "F.Fab")
		)
		(fp_line
			(start -0.12065 0.3048)
			(end -0.67945 0.3048)
			(stroke
				(width 0.1)
				(type default)
			)
			(layer "F.Fab")
		)
		(fp_line
			(start 0.120396 0.2794)
			(end -0.12065 0.2794)
			(stroke
				(width 0.1)
				(type default)
			)
			(layer "F.Fab")
		)
		(fp_line
			(start 0.120396 0.3048)
			(end 0.120396 0.2794)
			(stroke
				(width 0.1)
				(type default)
			)
			(layer "F.Fab")
		)
		(fp_line
			(start 0.12065 -0.3048)
			(end 0.67945 -0.3048)
			(stroke
				(width 0.1)
				(type default)
			)
			(layer "F.Fab")
		)
		(fp_line
			(start 0.12065 -0.2794)
			(end 0.12065 -0.3048)
			(stroke
				(width 0.1)
				(type default)
			)
			(layer "F.Fab")
		)
		(fp_line
			(start 0.67945 -0.3048)
			(end 0.67945 0.3048)
			(stroke
				(width 0.1)
				(type default)
			)
			(layer "F.Fab")
		)
		(fp_line
			(start 0.67945 0.3048)
			(end 0.120396 0.3048)
			(stroke
				(width 0.1)
				(type default)
			)
			(layer "F.Fab")
		)
		(pad "1" smd circle
			(at -0.40005 0)
			(size 0 0)
			(layers "F.Cu" "F.Mask" "F.Paste")
			(net "SPI_BIC1_MISO_R3")
		)
		(pad "2" smd circle
			(at 0.40005 0)
			(size 0 0)
			(layers "F.Cu" "F.Mask" "F.Paste")
			(net "SPI_BIC1_MISO_R2")
		)
	)
	(footprint ""
		(layer "F.Cu")
		(at 143.030194 -294.005508 -90)
		(property "Reference" "C3207"
			(at 0 0 270)
			(layer "F.SilkS")
			(hide yes)
			(effects
				(font
					(size 1.27 1.27)
				)
			)
		)
		(property "Value" ""
			(at 0 0 270)
			(layer "F.Fab")
			(effects
				(font
					(size 1.27 1.27)
				)
			)
		)
		(duplicate_pad_numbers_are_jumpers no)
		(fp_line
			(start -1.2954 0.5842)
			(end -1.2954 -0.5842)
			(stroke
				(width 0.1524)
				(type default)
			)
			(layer "F.SilkS")
		)
		(fp_line
			(start 1.2954 0.5842)
			(end -1.2954 0.5842)
			(stroke
				(width 0.1524)
				(type default)
			)
			(layer "F.SilkS")
		)
		(fp_line
			(start -1.2954 -0.5842)
			(end 1.2954 -0.5842)
			(stroke
				(width 0.1524)
				(type default)
			)
			(layer "F.SilkS")
		)
		(fp_line
			(start 1.2954 -0.5842)
			(end 1.2954 0.5842)
			(stroke
				(width 0.1524)
				(type default)
			)
			(layer "F.SilkS")
		)
		(fp_line
			(start -0.8636 0.4572)
			(end -0.8636 0.4064)
			(stroke
				(width 0.1)
				(type default)
			)
			(layer "F.Fab")
		)
		(fp_line
			(start 0.8636 0.4572)
			(end -0.8636 0.4572)
			(stroke
				(width 0.1)
				(type default)
			)
			(layer "F.Fab")
		)
		(fp_line
			(start -1.1938 0.4064)
			(end -1.1938 -0.4064)
			(stroke
				(width 0.1)
				(type default)
			)
			(layer "F.Fab")
		)
		(fp_line
			(start -0.8636 0.4064)
			(end -1.1938 0.4064)
			(stroke
				(width 0.1)
				(type default)
			)
			(layer "F.Fab")
		)
		(fp_line
			(start 0.8636 0.4064)
			(end 0.8636 0.4572)
			(stroke
				(width 0.1)
				(type default)
			)
			(layer "F.Fab")
		)
		(fp_line
			(start 1.1938 0.4064)
			(end 0.8636 0.4064)
			(stroke
				(width 0.1)
				(type default)
			)
			(layer "F.Fab")
		)
		(fp_line
			(start -1.1938 -0.4064)
			(end -0.8636 -0.4064)
			(stroke
				(width 0.1)
				(type default)
			)
			(layer "F.Fab")
		)
		(fp_line
			(start -0.8636 -0.4064)
			(end -0.8636 -0.4572)
			(stroke
				(width 0.1)
				(type default)
			)
			(layer "F.Fab")
		)
		(fp_line
			(start 0.8636 -0.4064)
			(end 1.1938 -0.4064)
			(stroke
				(width 0.1)
				(type default)
			)
			(layer "F.Fab")
		)
		(fp_line
			(start 1.1938 -0.4064)
			(end 1.1938 0.4064)
			(stroke
				(width 0.1)
				(type default)
			)
			(layer "F.Fab")
		)
		(fp_line
			(start -0.8636 -0.4572)
			(end 0.8636 -0.4572)
			(stroke
				(width 0.1)
				(type default)
			)
			(layer "F.Fab")
		)
		(fp_line
			(start 0.8636 -0.4572)
			(end 0.8636 -0.4064)
			(stroke
				(width 0.1)
				(type default)
			)
			(layer "F.Fab")
		)
		(pad "1" smd rect
			(at -0.7366 0 180)
			(size 0.7112 0.8128)
			(layers "F.Cu" "F.Mask" "F.Paste")
			(net "P1V8_PLL0_PEX1")
		)
		(pad "2" smd rect
			(at 0.7366 0 180)
			(size 0.7112 0.8128)
			(layers "F.Cu" "F.Mask" "F.Paste")
			(net "GND")
		)
	)
)
